(kicad_pcb
	(version 20260206)
	(generator "pcbnew")
	(generator_version "10.0")
	(general
		(thickness 1.6)
		(legacy_teardrops no)
	)
	(paper "A4")
	(title_block
		(title "01162023_DA0F0TEBIF0_F0T_Expander_BD_F_brd_V02_OCP.brd")
		(comment 1 "Grand Teton / footprints 3674-3681 of 9728")
	)
	(layers
		(0 "F.Cu" signal "TOP")
		(4 "In1.Cu" signal "GND")
		(6 "In2.Cu" signal "VCC")
		(8 "In3.Cu" signal "VCC1")
		(10 "In4.Cu" signal "GND1")
		(12 "In5.Cu" signal "IN1")
		(14 "In6.Cu" signal "GND2")
		(16 "In7.Cu" signal "IN2")
		(18 "In8.Cu" signal "GND3")
		(20 "In9.Cu" signal "IN3")
		(22 "In10.Cu" signal "GND4")
		(24 "In11.Cu" signal "IN4")
		(26 "In12.Cu" signal "GND5")
		(28 "In13.Cu" signal "IN5")
		(30 "In14.Cu" signal "GND6")
		(32 "In15.Cu" signal "IN6")
		(34 "In16.Cu" signal "GND7")
		(2 "B.Cu" signal "BOTTOM")
		(9 "F.Adhes" user "F.Adhesive")
		(11 "B.Adhes" user "B.Adhesive")
		(13 "F.Paste" user "Package Geometry/Pastemask Top")
		(15 "B.Paste" user "Package Geometry/Pastemask Bottom")
		(5 "F.SilkS" user "Ref Des/Silkscreen Top")
		(7 "B.SilkS" user "Ref Des/Silkscreen Bottom")
		(1 "F.Mask" user "Board Geometry/Soldermask Top")
		(3 "B.Mask" user "Board Geometry/Soldermask Bottom")
		(17 "Dwgs.User" user "User.Drawings")
		(19 "Cmts.User" user "User.Comments")
		(21 "Eco1.User" user "User.Eco1")
		(23 "Eco2.User" user "User.Eco2")
		(25 "Edge.Cuts" user "Board Geometry/Outline")
		(27 "Margin" user)
		(31 "F.CrtYd" user "Package Geometry/Place Bound Top")
		(29 "B.CrtYd" user "Package Geometry/Place Bound Bottom")
		(35 "F.Fab" user "Ref Des/Assembly Top")
		(33 "B.Fab" user "Ref Des/Assembly Bottom")
	)
	(footprint ""
		(layer "F.Cu")
		(at 450.650864 -374.4722 -90)
		(property "Reference" "R6687"
			(at 0 0 270)
			(layer "F.SilkS")
			(hide yes)
			(effects
				(font
					(size 1.27 1.27)
				)
			)
		)
		(property "Value" ""
			(at 0 0 270)
			(layer "F.Fab")
			(effects
				(font
					(size 1.27 1.27)
				)
			)
		)
		(duplicate_pad_numbers_are_jumpers no)
		(fp_line
			(start -0.7874 0.4064)
			(end -0.7874 -0.4064)
			(stroke
				(width 0.1524)
				(type default)
			)
			(layer "F.SilkS")
		)
		(fp_line
			(start 0.7874 0.4064)
			(end -0.7874 0.4064)
			(stroke
				(width 0.1524)
				(type default)
			)
			(layer "F.SilkS")
		)
		(fp_line
			(start -0.7874 -0.4064)
			(end 0.7874 -0.4064)
			(stroke
				(width 0.1524)
				(type default)
			)
			(layer "F.SilkS")
		)
		(fp_line
			(start 0.7874 -0.4064)
			(end 0.7874 0.4064)
			(stroke
				(width 0.1524)
				(type default)
			)
			(layer "F.SilkS")
		)
		(fp_line
			(start -0.67945 0.3048)
			(end -0.67945 -0.305054)
			(stroke
				(width 0.1)
				(type default)
			)
			(layer "F.Fab")
		)
		(fp_line
			(start -0.12065 0.3048)
			(end -0.67945 0.3048)
			(stroke
				(width 0.1)
				(type default)
			)
			(layer "F.Fab")
		)
		(fp_line
			(start 0.120396 0.3048)
			(end 0.120396 0.2794)
			(stroke
				(width 0.1)
				(type default)
			)
			(layer "F.Fab")
		)
		(fp_line
			(start 0.67945 0.3048)
			(end 0.120396 0.3048)
			(stroke
				(width 0.1)
				(type default)
			)
			(layer "F.Fab")
		)
		(fp_line
			(start -0.12065 0.2794)
			(end -0.12065 0.3048)
			(stroke
				(width 0.1)
				(type default)
			)
			(layer "F.Fab")
		)
		(fp_line
			(start 0.120396 0.2794)
			(end -0.12065 0.2794)
			(stroke
				(width 0.1)
				(type default)
			)
			(layer "F.Fab")
		)
		(fp_line
			(start -0.12065 -0.2794)
			(end 0.12065 -0.2794)
			(stroke
				(width 0.1)
				(type default)
			)
			(layer "F.Fab")
		)
		(fp_line
			(start 0.12065 -0.2794)
			(end 0.12065 -0.3048)
			(stroke
				(width 0.1)
				(type default)
			)
			(layer "F.Fab")
		)
		(fp_line
			(start 0.12065 -0.3048)
			(end 0.67945 -0.3048)
			(stroke
				(width 0.1)
				(type default)
			)
			(layer "F.Fab")
		)
		(fp_line
			(start 0.67945 -0.3048)
			(end 0.67945 0.3048)
			(stroke
				(width 0.1)
				(type default)
			)
			(layer "F.Fab")
		)
		(fp_line
			(start -0.67945 -0.305054)
			(end -0.12065 -0.305054)
			(stroke
				(width 0.1)
				(type default)
			)
			(layer "F.Fab")
		)
		(fp_line
			(start -0.12065 -0.305054)
			(end -0.12065 -0.2794)
			(stroke
				(width 0.1)
				(type default)
			)
			(layer "F.Fab")
		)
		(pad "1" smd circle
			(at -0.40005 0 270)
			(size 0 0)
			(layers "F.Cu" "F.Mask" "F.Paste")
			(net "GPU_3V3IO_RSVD3")
		)
		(pad "2" smd circle
			(at 0.40005 0 270)
			(size 0 0)
			(layers "F.Cu" "F.Mask" "F.Paste")
			(net "GND")
		)
	)
	(footprint ""
		(layer "F.Cu")
		(at 336.443574 -48.93691 180)
		(property "Reference" "R633"
			(at 0 0 180)
			(layer "F.SilkS")
			(hide yes)
			(effects
				(font
					(size 1.27 1.27)
				)
			)
		)
		(property "Value" ""
			(at 0 0 180)
			(layer "F.Fab")
			(effects
				(font
					(size 1.27 1.27)
				)
			)
		)
		(duplicate_pad_numbers_are_jumpers no)
		(fp_line
			(start 0.7874 0.4064)
			(end -0.7874 0.4064)
			(stroke
				(width 0.1524)
				(type default)
			)
			(layer "F.SilkS")
		)
		(fp_line
			(start 0.7874 -0.4064)
			(end 0.7874 0.4064)
			(stroke
				(width 0.1524)
				(type default)
			)
			(layer "F.SilkS")
		)
		(fp_line
			(start -0.7874 0.4064)
			(end -0.7874 -0.4064)
			(stroke
				(width 0.1524)
				(type default)
			)
			(layer "F.SilkS")
		)
		(fp_line
			(start -0.7874 -0.4064)
			(end 0.7874 -0.4064)
			(stroke
				(width 0.1524)
				(type default)
			)
			(layer "F.SilkS")
		)
		(fp_line
			(start 0.67945 0.3048)
			(end 0.120396 0.3048)
			(stroke
				(width 0.1)
				(type default)
			)
			(layer "F.Fab")
		)
		(fp_line
			(start 0.67945 -0.3048)
			(end 0.67945 0.3048)
			(stroke
				(width 0.1)
				(type default)
			)
			(layer "F.Fab")
		)
		(fp_line
			(start 0.12065 -0.2794)
			(end 0.12065 -0.3048)
			(stroke
				(width 0.1)
				(type default)
			)
			(layer "F.Fab")
		)
		(fp_line
			(start 0.12065 -0.3048)
			(end 0.67945 -0.3048)
			(stroke
				(width 0.1)
				(type default)
			)
			(layer "F.Fab")
		)
		(fp_line
			(start 0.120396 0.3048)
			(end 0.120396 0.2794)
			(stroke
				(width 0.1)
				(type default)
			)
			(layer "F.Fab")
		)
		(fp_line
			(start 0.120396 0.2794)
			(end -0.12065 0.2794)
			(stroke
				(width 0.1)
				(type default)
			)
			(layer "F.Fab")
		)
		(fp_line
			(start -0.12065 0.3048)
			(end -0.67945 0.3048)
			(stroke
				(width 0.1)
				(type default)
			)
			(layer "F.Fab")
		)
		(fp_line
			(start -0.12065 0.2794)
			(end -0.12065 0.3048)
			(stroke
				(width 0.1)
				(type default)
			)
			(layer "F.Fab")
		)
		(fp_line
			(start -0.12065 -0.2794)
			(end 0.12065 -0.2794)
			(stroke
				(width 0.1)
				(type default)
			)
			(layer "F.Fab")
		)
		(fp_line
			(start -0.12065 -0.305054)
			(end -0.12065 -0.2794)
			(stroke
				(width 0.1)
				(type default)
			)
			(layer "F.Fab")
		)
		(fp_line
			(start -0.67945 0.3048)
			(end -0.67945 -0.305054)
			(stroke
				(width 0.1)
				(type default)
			)
			(layer "F.Fab")
		)
		(fp_line
			(start -0.67945 -0.305054)
			(end -0.12065 -0.305054)
			(stroke
				(width 0.1)
				(type default)
			)
			(layer "F.Fab")
		)
		(pad "1" smd circle
			(at -0.40005 0 180)
			(size 0 0)
			(layers "F.Cu" "F.Mask" "F.Paste")
			(net "SMB_BIC_I2C6_MUX_SSD_8_15_ADC_R_SDA")
		)
		(pad "2" smd circle
			(at 0.40005 0 180)
			(size 0 0)
			(layers "F.Cu" "F.Mask" "F.Paste")
			(net "SMB_SSD11_ADC_SDA")
		)
	)
	(footprint ""
		(layer "F.Cu")
		(at 444.799466 -112.903508 90)
		(property "Reference" "PC826"
			(at 0 0 90)
			(layer "F.SilkS")
			(hide yes)
			(effects
				(font
					(size 1.27 1.27)
				)
			)
		)
		(property "Value" ""
			(at 0 0 90)
			(layer "F.Fab")
			(effects
				(font
					(size 1.27 1.27)
				)
			)
		)
		(duplicate_pad_numbers_are_jumpers no)
		(fp_line
			(start 1.524 -0.762)
			(end 1.524 0.762)
			(stroke
				(width 0.1524)
				(type default)
			)
			(layer "F.SilkS")
		)
		(fp_line
			(start -1.524 -0.762)
			(end 1.524 -0.762)
			(stroke
				(width 0.1524)
				(type default)
			)
			(layer "F.SilkS")
		)
		(fp_line
			(start 1.524 0.762)
			(end -1.524 0.762)
			(stroke
				(width 0.1524)
				(type default)
			)
			(layer "F.SilkS")
		)
		(fp_line
			(start -1.524 0.762)
			(end -1.524 -0.762)
			(stroke
				(width 0.1524)
				(type default)
			)
			(layer "F.SilkS")
		)
		(fp_line
			(start 1.1049 -0.724916)
			(end -1.1049 -0.724916)
			(stroke
				(width 0.1)
				(type default)
			)
			(layer "F.Fab")
		)
		(fp_line
			(start -1.1049 -0.724916)
			(end -1.1049 0.724916)
			(stroke
				(width 0.1)
				(type default)
			)
			(layer "F.Fab")
		)
		(fp_line
			(start 1.1049 0.724916)
			(end 1.1049 -0.724916)
			(stroke
				(width 0.1)
				(type default)
			)
			(layer "F.Fab")
		)
		(fp_line
			(start -1.1049 0.724916)
			(end 1.1049 0.724916)
			(stroke
				(width 0.1)
				(type default)
			)
			(layer "F.Fab")
		)
		(pad "1" smd rect
			(at -0.889 0 270)
			(size 1.016 1.27)
			(layers "F.Cu" "F.Mask" "F.Paste")
			(net "P12V_NIC7_R")
		)
		(pad "2" smd rect
			(at 0.889 0 270)
			(size 1.016 1.27)
			(layers "F.Cu" "F.Mask" "F.Paste")
			(net "GND")
		)
	)
	(footprint ""
		(layer "F.Cu")
		(at 132.026406 -121.408952 180)
		(property "Reference" "PC463"
			(at 0 0 180)
			(layer "F.SilkS")
			(hide yes)
			(effects
				(font
					(size 1.27 1.27)
				)
			)
		)
		(property "Value" ""
			(at 0 0 180)
			(layer "F.Fab")
			(effects
				(font
					(size 1.27 1.27)
				)
			)
		)
		(duplicate_pad_numbers_are_jumpers no)
		(fp_line
			(start 1.524 0.762)
			(end -1.524 0.762)
			(stroke
				(width 0.1524)
				(type default)
			)
			(layer "F.SilkS")
		)
		(fp_line
			(start 1.524 -0.762)
			(end 1.524 0.762)
			(stroke
				(width 0.1524)
				(type default)
			)
			(layer "F.SilkS")
		)
		(fp_line
			(start -1.524 0.762)
			(end -1.524 -0.762)
			(stroke
				(width 0.1524)
				(type default)
			)
			(layer "F.SilkS")
		)
		(fp_line
			(start -1.524 -0.762)
			(end 1.524 -0.762)
			(stroke
				(width 0.1524)
				(type default)
			)
			(layer "F.SilkS")
		)
		(fp_line
			(start 1.1049 0.724916)
			(end 1.1049 -0.724916)
			(stroke
				(width 0.1)
				(type default)
			)
			(layer "F.Fab")
		)
		(fp_line
			(start 1.1049 -0.724916)
			(end -1.1049 -0.724916)
			(stroke
				(width 0.1)
				(type default)
			)
			(layer "F.Fab")
		)
		(fp_line
			(start -1.1049 0.724916)
			(end 1.1049 0.724916)
			(stroke
				(width 0.1)
				(type default)
			)
			(layer "F.Fab")
		)
		(fp_line
			(start -1.1049 -0.724916)
			(end -1.1049 0.724916)
			(stroke
				(width 0.1)
				(type default)
			)
			(layer "F.Fab")
		)
		(pad "1" smd rect
			(at -0.889 0)
			(size 1.016 1.27)
			(layers "F.Cu" "F.Mask" "F.Paste")
			(net "GND")
		)
		(pad "2" smd rect
			(at 0.889 0)
			(size 1.016 1.27)
			(layers "F.Cu" "F.Mask" "F.Paste")
			(net "P3V3_AUX")
		)
	)
	(footprint ""
		(layer "F.Cu")
		(at 226.752912 -200.984104 -90)
		(property "Reference" "R465"
			(at 0 0 270)
			(layer "F.SilkS")
			(hide yes)
			(effects
				(font
					(size 1.27 1.27)
				)
			)
		)
		(property "Value" ""
			(at 0 0 270)
			(layer "F.Fab")
			(effects
				(font
					(size 1.27 1.27)
				)
			)
		)
		(duplicate_pad_numbers_are_jumpers no)
		(fp_line
			(start -0.7874 0.4064)
			(end -0.7874 -0.4064)
			(stroke
				(width 0.1524)
				(type default)
			)
			(layer "F.SilkS")
		)
		(fp_line
			(start 0.7874 0.4064)
			(end -0.7874 0.4064)
			(stroke
				(width 0.1524)
				(type default)
			)
			(layer "F.SilkS")
		)
		(fp_line
			(start -0.7874 -0.4064)
			(end 0.7874 -0.4064)
			(stroke
				(width 0.1524)
				(type default)
			)
			(layer "F.SilkS")
		)
		(fp_line
			(start 0.7874 -0.4064)
			(end 0.7874 0.4064)
			(stroke
				(width 0.1524)
				(type default)
			)
			(layer "F.SilkS")
		)
		(fp_line
			(start -0.67945 0.3048)
			(end -0.67945 -0.305054)
			(stroke
				(width 0.1)
				(type default)
			)
			(layer "F.Fab")
		)
		(fp_line
			(start -0.12065 0.3048)
			(end -0.67945 0.3048)
			(stroke
				(width 0.1)
				(type default)
			)
			(layer "F.Fab")
		)
		(fp_line
			(start 0.120396 0.3048)
			(end 0.120396 0.2794)
			(stroke
				(width 0.1)
				(type default)
			)
			(layer "F.Fab")
		)
		(fp_line
			(start 0.67945 0.3048)
			(end 0.120396 0.3048)
			(stroke
				(width 0.1)
				(type default)
			)
			(layer "F.Fab")
		)
		(fp_line
			(start -0.12065 0.2794)
			(end -0.12065 0.3048)
			(stroke
				(width 0.1)
				(type default)
			)
			(layer "F.Fab")
		)
		(fp_line
			(start 0.120396 0.2794)
			(end -0.12065 0.2794)
			(stroke
				(width 0.1)
				(type default)
			)
			(layer "F.Fab")
		)
		(fp_line
			(start -0.12065 -0.2794)
			(end 0.12065 -0.2794)
			(stroke
				(width 0.1)
				(type default)
			)
			(layer "F.Fab")
		)
		(fp_line
			(start 0.12065 -0.2794)
			(end 0.12065 -0.3048)
			(stroke
				(width 0.1)
				(type default)
			)
			(layer "F.Fab")
		)
		(fp_line
			(start 0.12065 -0.3048)
			(end 0.67945 -0.3048)
			(stroke
				(width 0.1)
				(type default)
			)
			(layer "F.Fab")
		)
		(fp_line
			(start 0.67945 -0.3048)
			(end 0.67945 0.3048)
			(stroke
				(width 0.1)
				(type default)
			)
			(layer "F.Fab")
		)
		(fp_line
			(start -0.67945 -0.305054)
			(end -0.12065 -0.305054)
			(stroke
				(width 0.1)
				(type default)
			)
			(layer "F.Fab")
		)
		(fp_line
			(start -0.12065 -0.305054)
			(end -0.12065 -0.2794)
			(stroke
				(width 0.1)
				(type default)
			)
			(layer "F.Fab")
		)
		(pad "1" smd circle
			(at -0.40005 0 270)
			(size 0 0)
			(layers "F.Cu" "F.Mask" "F.Paste")
			(net "SPI_BIC1_CS0_R_N")
		)
		(pad "2" smd circle
			(at 0.40005 0 270)
			(size 0 0)
			(layers "F.Cu" "F.Mask" "F.Paste")
			(net "SPI_BIC1_CS0_R1_N")
		)
	)
	(footprint ""
		(layer "F.Cu")
		(at 89.327482 -350.098614 90)
		(property "Reference" "C155"
			(at 0 0 90)
			(layer "F.SilkS")
			(hide yes)
			(effects
				(font
					(size 1.27 1.27)
				)
			)
		)
		(property "Value" ""
			(at 0 0 90)
			(layer "F.Fab")
			(effects
				(font
					(size 1.27 1.27)
				)
			)
		)
		(duplicate_pad_numbers_are_jumpers no)
		(fp_line
			(start 0.299974 -0.150114)
			(end 0.299974 0.150114)
			(stroke
				(width 0.1)
				(type default)
			)
			(layer "F.Fab")
		)
		(fp_line
			(start -0.299974 -0.150114)
			(end 0.299974 -0.150114)
			(stroke
				(width 0.1)
				(type default)
			)
			(layer "F.Fab")
		)
		(fp_line
			(start 0.299974 0.150114)
			(end -0.299974 0.150114)
			(stroke
				(width 0.1)
				(type default)
			)
			(layer "F.Fab")
		)
		(fp_line
			(start -0.299974 0.150114)
			(end -0.299974 -0.150114)
			(stroke
				(width 0.1)
				(type default)
			)
			(layer "F.Fab")
		)
		(pad "1" smd rect
			(at -0.2667 0 90)
			(size 0.3048 0.381)
			(layers "F.Cu" "F.Mask" "F.Paste")
			(net "P5E_PEX0_STN6_TX_DP<98>")
		)
		(pad "2" smd rect
			(at 0.2667 0 90)
			(size 0.3048 0.381)
			(layers "F.Cu" "F.Mask" "F.Paste")
			(net "P5E_PEX0_STN6_TX_C_DP<98>")
		)
	)
	(footprint ""
		(layer "F.Cu")
		(at 262.564626 -238.968788 90)
		(property "Reference" "R6579"
			(at 0 0 90)
			(layer "F.SilkS")
			(hide yes)
			(effects
				(font
					(size 1.27 1.27)
				)
			)
		)
		(property "Value" ""
			(at 0 0 90)
			(layer "F.Fab")
			(effects
				(font
					(size 1.27 1.27)
				)
			)
		)
		(duplicate_pad_numbers_are_jumpers no)
		(fp_line
			(start 0.7874 -0.4064)
			(end 0.7874 0.4064)
			(stroke
				(width 0.1524)
				(type default)
			)
			(layer "F.SilkS")
		)
		(fp_line
			(start -0.7874 -0.4064)
			(end 0.7874 -0.4064)
			(stroke
				(width 0.1524)
				(type default)
			)
			(layer "F.SilkS")
		)
		(fp_line
			(start 0.7874 0.4064)
			(end -0.7874 0.4064)
			(stroke
				(width 0.1524)
				(type default)
			)
			(layer "F.SilkS")
		)
		(fp_line
			(start -0.7874 0.4064)
			(end -0.7874 -0.4064)
			(stroke
				(width 0.1524)
				(type default)
			)
			(layer "F.SilkS")
		)
		(fp_line
			(start -0.12065 -0.305054)
			(end -0.12065 -0.2794)
			(stroke
				(width 0.1)
				(type default)
			)
			(layer "F.Fab")
		)
		(fp_line
			(start -0.67945 -0.305054)
			(end -0.12065 -0.305054)
			(stroke
				(width 0.1)
				(type default)
			)
			(layer "F.Fab")
		)
		(fp_line
			(start 0.67945 -0.3048)
			(end 0.67945 0.3048)
			(stroke
				(width 0.1)
				(type default)
			)
			(layer "F.Fab")
		)
		(fp_line
			(start 0.12065 -0.3048)
			(end 0.67945 -0.3048)
			(stroke
				(width 0.1)
				(type default)
			)
			(layer "F.Fab")
		)
		(fp_line
			(start 0.12065 -0.2794)
			(end 0.12065 -0.3048)
			(stroke
				(width 0.1)
				(type default)
			)
			(layer "F.Fab")
		)
		(fp_line
			(start -0.12065 -0.2794)
			(end 0.12065 -0.2794)
			(stroke
				(width 0.1)
				(type default)
			)
			(layer "F.Fab")
		)
		(fp_line
			(start 0.120396 0.2794)
			(end -0.12065 0.2794)
			(stroke
				(width 0.1)
				(type default)
			)
			(layer "F.Fab")
		)
		(fp_line
			(start -0.12065 0.2794)
			(end -0.12065 0.3048)
			(stroke
				(width 0.1)
				(type default)
			)
			(layer "F.Fab")
		)
		(fp_line
			(start 0.67945 0.3048)
			(end 0.120396 0.3048)
			(stroke
				(width 0.1)
				(type default)
			)
			(layer "F.Fab")
		)
		(fp_line
			(start 0.120396 0.3048)
			(end 0.120396 0.2794)
			(stroke
				(width 0.1)
				(type default)
			)
			(layer "F.Fab")
		)
		(fp_line
			(start -0.12065 0.3048)
			(end -0.67945 0.3048)
			(stroke
				(width 0.1)
				(type default)
			)
			(layer "F.Fab")
		)
		(fp_line
			(start -0.67945 0.3048)
			(end -0.67945 -0.305054)
			(stroke
				(width 0.1)
				(type default)
			)
			(layer "F.Fab")
		)
		(pad "1" smd circle
			(at -0.40005 0 90)
			(size 0 0)
			(layers "F.Cu" "F.Mask" "F.Paste")
			(net "P1V8_PLL0_PEX2")
		)
		(pad "2" smd circle
			(at 0.40005 0 90)
			(size 0 0)
			(layers "F.Cu" "F.Mask" "F.Paste")
			(net "P1V8_PLL_PEX2_ADJ")
		)
	)
	(footprint ""
		(layer "F.Cu")
		(at 481.221288 -553.346874 180)
		(property "Reference" "SCREW_SSD12_2"
			(at -5.6007 -1.402334 0)
			(unlocked yes)
			(layer "B.SilkS")
			(effects
				(font
					(size 0.7874 0.5842)
					(thickness 0.1524)
				)
				(justify mirror)
			)
		)
		(property "Value" ""
			(at 0 0 180)
			(layer "F.Fab")
			(effects
				(font
					(size 1.27 1.27)
				)
			)
		)
		(duplicate_pad_numbers_are_jumpers no)
		(pad "1" thru_hole circle
			(at 0 0 180)
			(size 0.4572 0.4572)
			(drill 0.2032)
			(layers "*.Cu" "*.Mask")
			(remove_unused_layers no)
			(net "Net_9149")
			(clearance 0.127)
			(thermal_gap 0.127)
			(padstack
				(mode front_inner_back)
				(layer "Inner"
					(shape circle)
					(size 0.4572 0.4572)
					(clearance 0.127)
				)
				(layer "B.Cu"
					(shape circle)
					(size 0.508 0.508)
					(clearance 0.1016)
				)
			)
		)
	)
)
